FILE_TYPE = MULTI_PHYS_TABLE;

PART 'NC7SB3157P6X'

{========================================================================================}
:VALUE          | PART_TYPE | MATERIAL | PART_NUMBER    = STANDARD    | LIFECYCLE      | PART_NUMBER   | JEDEC_TYPE | DESCRIPTION                        | MANUFTR | MANUF_PN       | RD_CMPLS_LVL | CMPLS_LVL | FROM_PJ    | CLASS | DIP_SMD | DATA                   | EE_CHECK_LIST | FP_ECN | PSL | CREATOR | STATUS | MSD | ESD_CDM | ESD_HBM | ESD_MM | PIN_LENGTH_SHORT_PIN | PIN_LENGTH_LONG_PIN | CREATEDAY  ;
{========================================================================================}
 'NC7SB3157P6X' | 'SMLF'    | 'IC'     | 'ALSB3157000'(!) = 'End of Design'  | 'Comp-Approve'   | 'ALSB3157000' |'SC70-6XA'| 'IC OTHER(6P)NC7SB3157P6X(SC70-6)' | 'FAC'   | 'NC7SB3157P6X' | 'EP(V1)'     | 'EP(V1)'  | 'T52-NICK' | 'IC'  | ''      | 'FAC_NC7SB3157P6X.pdf' | ''            | ''     | ''  | ''      | ''     | ''  | ''      | ''      | ''     | '0 MILS'             | '0 MILS'            | '20210604'
 'NC7SB3157P6X' | 'SMLF'    | 'EMPTY'  | 'ALSB3157000'(!) = 'End of Design'  | 'Comp-Approve'   | 'ALSB3157000' |'SC70-6XA'| 'IC OTHER(6P)NC7SB3157P6X(SC70-6)' | 'FAC'   | 'NC7SB3157P6X' | 'EP(V1)'     | 'EP(V1)'  | 'T52-NICK' | 'IC'  | ''      | 'FAC_NC7SB3157P6X.pdf' | ''            | ''     | ''  | ''      | ''     | ''  | ''      | ''      | ''     | '0 MILS'             | '0 MILS'            | '20210604'

END_PART

END.

